(kicad_pcb
	(version 20260206)
	(generator "pcbnew")
	(generator_version "10.0")
	(general
		(thickness 1.6)
		(legacy_teardrops no)
	)
	(paper "A4")
	(title_block
		(title "04192023_DAF0TMB3IC0_F0TG_MB_C_brd_V02_OCP.brd")
		(comment 1 "Grand Teton / footprints 1268-1271 of 8354")
	)
	(layers
		(0 "F.Cu" signal "TOP")
		(4 "In1.Cu" signal "GND")
		(6 "In2.Cu" signal "IN1")
		(8 "In3.Cu" signal "GND1")
		(10 "In4.Cu" signal "IN2")
		(12 "In5.Cu" signal "GND2")
		(14 "In6.Cu" signal "IN3")
		(16 "In7.Cu" signal "GND3")
		(18 "In8.Cu" signal "VCC")
		(20 "In9.Cu" signal "VCC1")
		(22 "In10.Cu" signal "GND4")
		(24 "In11.Cu" signal "IN4")
		(26 "In12.Cu" signal "GND5")
		(28 "In13.Cu" signal "IN5")
		(30 "In14.Cu" signal "GND6")
		(32 "In15.Cu" signal "IN6")
		(34 "In16.Cu" signal "GND7")
		(2 "B.Cu" signal "BOTTOM")
		(9 "F.Adhes" user "F.Adhesive")
		(11 "B.Adhes" user "B.Adhesive")
		(13 "F.Paste" user "Package Geometry/Pastemask Top")
		(15 "B.Paste" user "Package Geometry/Pastemask Bottom")
		(5 "F.SilkS" user "Ref Des/Silkscreen Top")
		(7 "B.SilkS" user "Ref Des/Silkscreen Bottom")
		(1 "F.Mask" user "Board Geometry/Soldermask Top")
		(3 "B.Mask" user "Board Geometry/Soldermask Bottom")
		(17 "Dwgs.User" user "User.Drawings")
		(19 "Cmts.User" user "User.Comments")
		(21 "Eco1.User" user "User.Eco1")
		(23 "Eco2.User" user "User.Eco2")
		(25 "Edge.Cuts" user "Board Geometry/Outline")
		(27 "Margin" user)
		(31 "F.CrtYd" user "Package Geometry/Place Bound Top")
		(29 "B.CrtYd" user "Package Geometry/Place Bound Bottom")
		(35 "F.Fab" user "Ref Des/Assembly Top")
		(33 "B.Fab" user "Ref Des/Assembly Bottom")
	)
	(footprint ""
		(layer "F.Cu")
		(at 185.278522 -401.919694 -90)
		(property "Reference" "PU289"
			(at 3.212592 -5.588762 0)
			(unlocked yes)
			(layer "F.SilkS")
			(effects
				(font
					(size 0.7874 0.5842)
					(thickness 0.1524)
				)
			)
		)
		(property "Value" ""
			(at 0 0 270)
			(layer "F.Fab")
			(effects
				(font
					(size 1.27 1.27)
				)
			)
		)
		(duplicate_pad_numbers_are_jumpers no)
		(fp_line
			(start -2.567686 3.567684)
			(end 2.567686 3.567684)
			(stroke
				(width 0.1524)
				(type default)
			)
			(layer "F.SilkS")
		)
		(fp_line
			(start 2.567686 3.567684)
			(end 2.567686 -3.567684)
			(stroke
				(width 0.1524)
				(type default)
			)
			(layer "F.SilkS")
		)
		(fp_line
			(start -2.567686 -3.567684)
			(end -2.567686 3.567684)
			(stroke
				(width 0.1524)
				(type default)
			)
			(layer "F.SilkS")
		)
		(fp_line
			(start 2.567686 -3.567684)
			(end -2.567686 -3.567684)
			(stroke
				(width 0.1524)
				(type default)
			)
			(layer "F.SilkS")
		)
		(fp_poly
			(pts
				(xy -2.736088 -2.894076) (xy -3.852926 -3.100324) (xy -3.241548 -3.9116)
			)
			(stroke
				(width 0)
				(type default)
			)
			(fill yes)
			(layer "F.SilkS")
		)
		(fp_line
			(start -2.549906 3.549904)
			(end 2.549906 3.549904)
			(stroke
				(width 0.1)
				(type default)
			)
			(layer "F.Fab")
		)
		(fp_line
			(start 2.549906 3.549904)
			(end 2.549906 -3.549904)
			(stroke
				(width 0.1)
				(type default)
			)
			(layer "F.Fab")
		)
		(fp_line
			(start -2.549906 -3.549904)
			(end -2.549906 3.549904)
			(stroke
				(width 0.1)
				(type default)
			)
			(layer "F.Fab")
		)
		(fp_line
			(start 2.549906 -3.549904)
			(end -2.549906 -3.549904)
			(stroke
				(width 0.1)
				(type default)
			)
			(layer "F.Fab")
		)
		(fp_poly
			(pts
				(xy -3.7592 -3.20802) (xy -3.7592 -2.19202) (xy -2.7432 -2.70002)
			)
			(stroke
				(width 0)
				(type default)
			)
			(fill yes)
			(layer "F.Fab")
		)
		(pad "1" smd rect
			(at -2.237486 -2.70002)
			(size 0.2286 0.381)
			(layers "F.Cu" "F.Mask" "F.Paste")
			(net "P12V_PSU")
		)
		(pad "2" smd rect
			(at -2.237486 -2.249932)
			(size 0.2286 0.381)
			(layers "F.Cu" "F.Mask" "F.Paste")
			(net "P12V_PSU")
		)
		(pad "3" smd rect
			(at -2.237486 -1.800098)
			(size 0.2286 0.381)
			(layers "F.Cu" "F.Mask" "F.Paste")
			(net "P12V_PSU")
		)
		(pad "4" smd rect
			(at -2.237486 -1.35001)
			(size 0.2286 0.381)
			(layers "F.Cu" "F.Mask" "F.Paste")
			(net "P12V_PSU")
		)
		(pad "5" smd rect
			(at -2.237486 -0.899922)
			(size 0.2286 0.381)
			(layers "F.Cu" "F.Mask" "F.Paste")
			(net "P12V_PSU")
		)
		(pad "6" smd rect
			(at -2.237486 -0.450088)
			(size 0.2286 0.381)
			(layers "F.Cu" "F.Mask" "F.Paste")
			(net "P12V_PSU")
		)
		(pad "7" smd rect
			(at -2.237486 0)
			(size 0.2286 0.381)
			(layers "F.Cu" "F.Mask" "F.Paste")
			(net "P12V_PSU")
		)
		(pad "8" smd rect
			(at -2.237486 0.450088)
			(size 0.2286 0.381)
			(layers "F.Cu" "F.Mask" "F.Paste")
			(net "P12V_PSU")
		)
		(pad "9" smd rect
			(at -2.237486 0.899922)
			(size 0.2286 0.381)
			(layers "F.Cu" "F.Mask" "F.Paste")
			(net "HSC_VSENSE")
		)
		(pad "10" smd rect
			(at -2.237486 1.35001)
			(size 0.2286 0.381)
			(layers "F.Cu" "F.Mask" "F.Paste")
			(net "IRQ_SML1_PMBUS_ALERT")
		)
		(pad "11" smd rect
			(at -2.237486 1.800098)
			(size 0.2286 0.381)
			(layers "F.Cu" "F.Mask" "F.Paste")
			(net "SMB_SML1_PMBUS_HSC_L_SCL")
		)
		(pad "12" smd rect
			(at -2.237486 2.249932)
			(size 0.2286 0.381)
			(layers "F.Cu" "F.Mask" "F.Paste")
			(net "SMB_SML1_PMBUS_HSC_R_SDA")
		)
		(pad "13" smd rect
			(at -2.237486 2.70002)
			(size 0.2286 0.381)
			(layers "F.Cu" "F.Mask" "F.Paste")
			(net "MB0_P12V_STBY_PWRGD")
		)
		(pad "14" smd rect
			(at -1.575054 3.237484 270)
			(size 0.2286 0.381)
			(layers "F.Cu" "F.Mask" "F.Paste")
			(net "HSC_VIN_UVW_N")
		)
		(pad "15" smd rect
			(at -1.124966 3.237484 270)
			(size 0.2286 0.381)
			(layers "F.Cu" "F.Mask" "F.Paste")
			(net "HSC_VTEMP")
		)
		(pad "16" smd rect
			(at -0.674878 3.237484 270)
			(size 0.2286 0.381)
			(layers "F.Cu" "F.Mask" "F.Paste")
			(net "HSC_SS")
		)
		(pad "17" smd rect
			(at -0.225044 3.237484 270)
			(size 0.2286 0.381)
			(layers "F.Cu" "F.Mask" "F.Paste")
			(net "HSC_VDD_R")
		)
		(pad "18" smd rect
			(at 0.225044 3.237484 270)
			(size 0.2286 0.381)
			(layers "F.Cu" "F.Mask" "F.Paste")
			(net "AGND_HSC")
		)
		(pad "19" smd rect
			(at 0.674878 3.237484 270)
			(size 0.2286 0.381)
			(layers "F.Cu" "F.Mask" "F.Paste")
			(net "HSC_VDD18")
		)
		(pad "20" smd rect
			(at 1.124966 3.237484 270)
			(size 0.2286 0.381)
			(layers "F.Cu" "F.Mask" "F.Paste")
			(net "HSC_CS")
		)
		(pad "21" smd rect
			(at 1.575054 3.237484 270)
			(size 0.2286 0.381)
			(layers "F.Cu" "F.Mask" "F.Paste")
			(net "HSC_IMON")
		)
		(pad "22" smd rect
			(at 2.237486 2.70002)
			(size 0.2286 0.381)
			(layers "F.Cu" "F.Mask" "F.Paste")
			(net "HSC_OCREF")
		)
		(pad "23" smd rect
			(at 2.237486 2.249932)
			(size 0.2286 0.381)
			(layers "F.Cu" "F.Mask" "F.Paste")
			(net "HSC_ADDR")
		)
		(pad "24" smd rect
			(at 2.237486 1.800098)
			(size 0.2286 0.381)
			(layers "F.Cu" "F.Mask" "F.Paste")
			(net "HSC_VOSEN")
		)
		(pad "25" smd rect
			(at 2.237486 1.35001)
			(size 0.2286 0.381)
			(layers "F.Cu" "F.Mask" "F.Paste")
			(net "HSC_SCREF")
		)
		(pad "26" smd rect
			(at 2.237486 0.899922)
			(size 0.2286 0.381)
			(layers "F.Cu" "F.Mask" "F.Paste")
			(net "HSC_EN_R")
		)
		(pad "27" smd rect
			(at 2.237486 0.450088)
			(size 0.2286 0.381)
			(layers "F.Cu" "F.Mask" "F.Paste")
			(net "P12V_AUX")
		)
		(pad "28" smd rect
			(at 2.237486 0)
			(size 0.2286 0.381)
			(layers "F.Cu" "F.Mask" "F.Paste")
			(net "P12V_AUX")
		)
		(pad "29" smd rect
			(at 2.237486 -0.450088)
			(size 0.2286 0.381)
			(layers "F.Cu" "F.Mask" "F.Paste")
			(net "P12V_AUX")
		)
		(pad "30" smd rect
			(at 2.237486 -0.899922)
			(size 0.2286 0.381)
			(layers "F.Cu" "F.Mask" "F.Paste")
			(net "P12V_AUX")
		)
		(pad "31" smd rect
			(at 2.237486 -1.35001)
			(size 0.2286 0.381)
			(layers "F.Cu" "F.Mask" "F.Paste")
			(net "P12V_AUX")
		)
		(pad "32" smd rect
			(at 2.237486 -1.800098)
			(size 0.2286 0.381)
			(layers "F.Cu" "F.Mask" "F.Paste")
			(net "P12V_AUX")
		)
		(pad "33" smd rect
			(at 2.237486 -2.249932)
			(size 0.2286 0.381)
			(layers "F.Cu" "F.Mask" "F.Paste")
			(net "P12V_AUX")
		)
		(pad "34" smd rect
			(at 2.237486 -2.70002)
			(size 0.2286 0.381)
			(layers "F.Cu" "F.Mask" "F.Paste")
			(net "P12V_AUX")
		)
		(pad "35" smd rect
			(at 1.575054 -3.237484 270)
			(size 0.2286 0.381)
			(layers "F.Cu" "F.Mask" "F.Paste")
			(net "P12V_AUX")
		)
		(pad "36" smd rect
			(at 1.124966 -3.237484 270)
			(size 0.2286 0.381)
			(layers "F.Cu" "F.Mask" "F.Paste")
			(net "P12V_AUX")
		)
		(pad "37" smd rect
			(at 0.674878 -3.237484 270)
			(size 0.2286 0.381)
			(layers "F.Cu" "F.Mask" "F.Paste")
			(net "HSC_D_OC_R")
		)
		(pad "38" smd rect
			(at 0.225044 -3.237484 270)
			(size 0.2286 0.381)
			(layers "F.Cu" "F.Mask" "F.Paste")
			(net "HSC_ON_R")
		)
		(pad "39" smd rect
			(at -0.225044 -3.237484 270)
			(size 0.2286 0.381)
			(layers "F.Cu" "F.Mask" "F.Paste")
			(net "HSC_FAULT")
		)
		(pad "40" smd rect
			(at -0.674878 -3.237484 270)
			(size 0.2286 0.381)
			(layers "F.Cu" "F.Mask" "F.Paste")
			(net "HSC_FLT_TYPE")
		)
		(pad "41" smd rect
			(at -1.124966 -3.237484 270)
			(size 0.2286 0.381)
			(layers "F.Cu" "F.Mask" "F.Paste")
			(net "HSC_MODE")
		)
		(pad "42" smd rect
			(at -1.575054 -3.237484 270)
			(size 0.2286 0.381)
			(layers "F.Cu" "F.Mask" "F.Paste")
			(net "P12V_PSU")
		)
		(pad "43" smd rect
			(at 0 -0.999998 270)
			(size 3.4036 3.4036)
			(layers "F.Cu" "F.Mask" "F.Paste")
			(net "P12V_PSU")
		)
		(pad "44" smd rect
			(at -1.124966 1.89992 270)
			(size 1.1684 1.6002)
			(layers "F.Cu" "F.Mask" "F.Paste")
			(net "AGND_HSC")
		)
		(pad "45" smd rect
			(at 1.124966 1.89992 270)
			(size 1.1684 1.6002)
			(layers "F.Cu" "F.Mask" "F.Paste")
			(net "HSC_VDD_R")
		)
		(zone
			(layer "F.Cu")
			(hatch none 0.5)
			(connect_pads
				(clearance 0)
			)
			(min_thickness 0.25)
			(keepout
				(tracks not_allowed)
				(vias allowed)
				(pads allowed)
				(copperpour not_allowed)
				(footprints allowed)
			)
			(placement
				(enabled no)
				(sheetname "")
			)
			(fill
				(thermal_gap 0.5)
				(thermal_bridge_width 0.5)
				(island_removal_mode 0)
			)
			(polygon
				(pts
					(xy 182.282338 -403.91588) (xy 184.52592 -403.91588) (xy 184.52592 -402.961094) (xy 184.229502 -402.961094)
					(xy 184.229502 -403.67966) (xy 182.527702 -403.67966) (xy 182.527702 -402.40966) (xy 184.229502 -402.40966)
					(xy 184.229502 -402.935694) (xy 184.52592 -402.935694) (xy 184.52592 -400.776694) (xy 184.229502 -400.776694)
					(xy 184.229502 -401.429728) (xy 182.527702 -401.429728) (xy 182.527702 -400.159728) (xy 184.229502 -400.159728)
					(xy 184.229502 -400.751294) (xy 184.52592 -400.751294) (xy 184.52592 -400.167094) (xy 188.03112 -400.167094)
					(xy 188.03112 -403.23008) (xy 188.274706 -403.23008) (xy 188.274706 -399.923508) (xy 182.282338 -399.923508)
				)
			)
		)
	)
	(footprint ""
		(layer "F.Cu")
		(at 365.62792 -396.146274)
		(property "Reference" "R615"
			(at 0 0 0)
			(layer "F.SilkS")
			(hide yes)
			(effects
				(font
					(size 1.27 1.27)
				)
			)
		)
		(property "Value" ""
			(at 0 0 0)
			(layer "F.Fab")
			(effects
				(font
					(size 1.27 1.27)
				)
			)
		)
		(duplicate_pad_numbers_are_jumpers no)
		(fp_line
			(start -0.32512 -0.175006)
			(end 0.32512 -0.175006)
			(stroke
				(width 0.1)
				(type default)
			)
			(layer "F.Fab")
		)
		(fp_line
			(start -0.32512 0.175006)
			(end -0.32512 -0.175006)
			(stroke
				(width 0.1)
				(type default)
			)
			(layer "F.Fab")
		)
		(fp_line
			(start 0.32512 -0.175006)
			(end 0.32512 0.175006)
			(stroke
				(width 0.1)
				(type default)
			)
			(layer "F.Fab")
		)
		(fp_line
			(start 0.32512 0.175006)
			(end -0.32512 0.175006)
			(stroke
				(width 0.1)
				(type default)
			)
			(layer "F.Fab")
		)
		(pad "1" smd rect
			(at -0.2667 0)
			(size 0.3048 0.381)
			(layers "F.Cu" "F.Mask" "F.Paste")
			(net "CLK_100M_RETIMER_CPU0_P3_R_DP")
		)
		(pad "2" smd rect
			(at 0.2667 0 180)
			(size 0.3048 0.381)
			(layers "F.Cu" "F.Mask" "F.Paste")
			(net "CLK_100M_RETIMER_CPU0_P3_DP")
		)
	)
	(footprint ""
		(layer "F.Cu")
		(at 60.011564 -16.220948 -90)
		(property "Reference" "R3172"
			(at 0 0 270)
			(layer "F.SilkS")
			(hide yes)
			(effects
				(font
					(size 1.27 1.27)
				)
			)
		)
		(property "Value" ""
			(at 0 0 270)
			(layer "F.Fab")
			(effects
				(font
					(size 1.27 1.27)
				)
			)
		)
		(duplicate_pad_numbers_are_jumpers no)
		(fp_line
			(start -0.7874 0.4064)
			(end -0.7874 -0.4064)
			(stroke
				(width 0.1524)
				(type default)
			)
			(layer "F.SilkS")
		)
		(fp_line
			(start 0.7874 0.4064)
			(end -0.7874 0.4064)
			(stroke
				(width 0.1524)
				(type default)
			)
			(layer "F.SilkS")
		)
		(fp_line
			(start -0.7874 -0.4064)
			(end 0.7874 -0.4064)
			(stroke
				(width 0.1524)
				(type default)
			)
			(layer "F.SilkS")
		)
		(fp_line
			(start 0.7874 -0.4064)
			(end 0.7874 0.4064)
			(stroke
				(width 0.1524)
				(type default)
			)
			(layer "F.SilkS")
		)
		(fp_line
			(start -0.67945 0.3048)
			(end -0.67945 -0.305054)
			(stroke
				(width 0.1)
				(type default)
			)
			(layer "F.Fab")
		)
		(fp_line
			(start -0.12065 0.3048)
			(end -0.67945 0.3048)
			(stroke
				(width 0.1)
				(type default)
			)
			(layer "F.Fab")
		)
		(fp_line
			(start 0.120396 0.3048)
			(end 0.120396 0.2794)
			(stroke
				(width 0.1)
				(type default)
			)
			(layer "F.Fab")
		)
		(fp_line
			(start 0.67945 0.3048)
			(end 0.120396 0.3048)
			(stroke
				(width 0.1)
				(type default)
			)
			(layer "F.Fab")
		)
		(fp_line
			(start -0.12065 0.2794)
			(end -0.12065 0.3048)
			(stroke
				(width 0.1)
				(type default)
			)
			(layer "F.Fab")
		)
		(fp_line
			(start 0.120396 0.2794)
			(end -0.12065 0.2794)
			(stroke
				(width 0.1)
				(type default)
			)
			(layer "F.Fab")
		)
		(fp_line
			(start -0.12065 -0.2794)
			(end 0.12065 -0.2794)
			(stroke
				(width 0.1)
				(type default)
			)
			(layer "F.Fab")
		)
		(fp_line
			(start 0.12065 -0.2794)
			(end 0.12065 -0.3048)
			(stroke
				(width 0.1)
				(type default)
			)
			(layer "F.Fab")
		)
		(fp_line
			(start 0.12065 -0.3048)
			(end 0.67945 -0.3048)
			(stroke
				(width 0.1)
				(type default)
			)
			(layer "F.Fab")
		)
		(fp_line
			(start 0.67945 -0.3048)
			(end 0.67945 0.3048)
			(stroke
				(width 0.1)
				(type default)
			)
			(layer "F.Fab")
		)
		(fp_line
			(start -0.67945 -0.305054)
			(end -0.12065 -0.305054)
			(stroke
				(width 0.1)
				(type default)
			)
			(layer "F.Fab")
		)
		(fp_line
			(start -0.12065 -0.305054)
			(end -0.12065 -0.2794)
			(stroke
				(width 0.1)
				(type default)
			)
			(layer "F.Fab")
		)
		(pad "1" smd circle
			(at -0.40005 0 270)
			(size 0 0)
			(layers "F.Cu" "F.Mask" "F.Paste")
			(net "OCP_V3_2_AUX_PWR_EN")
		)
		(pad "2" smd circle
			(at 0.40005 0 270)
			(size 0 0)
			(layers "F.Cu" "F.Mask" "F.Paste")
			(net "OCP_V3_2_AUX_PWR_EN_R")
		)
	)
	(footprint ""
		(layer "F.Cu")
		(at 197.876922 -76.016866)
		(property "Reference" "R77"
			(at 0 0 0)
			(layer "F.SilkS")
			(hide yes)
			(effects
				(font
					(size 1.27 1.27)
				)
			)
		)
		(property "Value" ""
			(at 0 0 0)
			(layer "F.Fab")
			(effects
				(font
					(size 1.27 1.27)
				)
			)
		)
		(duplicate_pad_numbers_are_jumpers no)
		(fp_line
			(start -0.7874 -0.4064)
			(end 0.7874 -0.4064)
			(stroke
				(width 0.1524)
				(type default)
			)
			(layer "F.SilkS")
		)
		(fp_line
			(start -0.7874 0.4064)
			(end -0.7874 -0.4064)
			(stroke
				(width 0.1524)
				(type default)
			)
			(layer "F.SilkS")
		)
		(fp_line
			(start 0.7874 -0.4064)
			(end 0.7874 0.4064)
			(stroke
				(width 0.1524)
				(type default)
			)
			(layer "F.SilkS")
		)
		(fp_line
			(start 0.7874 0.4064)
			(end -0.7874 0.4064)
			(stroke
				(width 0.1524)
				(type default)
			)
			(layer "F.SilkS")
		)
		(fp_line
			(start -0.67945 -0.305054)
			(end -0.12065 -0.305054)
			(stroke
				(width 0.1)
				(type default)
			)
			(layer "F.Fab")
		)
		(fp_line
			(start -0.67945 0.3048)
			(end -0.67945 -0.305054)
			(stroke
				(width 0.1)
				(type default)
			)
			(layer "F.Fab")
		)
		(fp_line
			(start -0.12065 -0.305054)
			(end -0.12065 -0.2794)
			(stroke
				(width 0.1)
				(type default)
			)
			(layer "F.Fab")
		)
		(fp_line
			(start -0.12065 -0.2794)
			(end 0.12065 -0.2794)
			(stroke
				(width 0.1)
				(type default)
			)
			(layer "F.Fab")
		)
		(fp_line
			(start -0.12065 0.2794)
			(end -0.12065 0.3048)
			(stroke
				(width 0.1)
				(type default)
			)
			(layer "F.Fab")
		)
		(fp_line
			(start -0.12065 0.3048)
			(end -0.67945 0.3048)
			(stroke
				(width 0.1)
				(type default)
			)
			(layer "F.Fab")
		)
		(fp_line
			(start 0.120396 0.2794)
			(end -0.12065 0.2794)
			(stroke
				(width 0.1)
				(type default)
			)
			(layer "F.Fab")
		)
		(fp_line
			(start 0.120396 0.3048)
			(end 0.120396 0.2794)
			(stroke
				(width 0.1)
				(type default)
			)
			(layer "F.Fab")
		)
		(fp_line
			(start 0.12065 -0.3048)
			(end 0.67945 -0.3048)
			(stroke
				(width 0.1)
				(type default)
			)
			(layer "F.Fab")
		)
		(fp_line
			(start 0.12065 -0.2794)
			(end 0.12065 -0.3048)
			(stroke
				(width 0.1)
				(type default)
			)
			(layer "F.Fab")
		)
		(fp_line
			(start 0.67945 -0.3048)
			(end 0.67945 0.3048)
			(stroke
				(width 0.1)
				(type default)
			)
			(layer "F.Fab")
		)
		(fp_line
			(start 0.67945 0.3048)
			(end 0.120396 0.3048)
			(stroke
				(width 0.1)
				(type default)
			)
			(layer "F.Fab")
		)
		(pad "1" smd circle
			(at -0.40005 0)
			(size 0 0)
			(layers "F.Cu" "F.Mask" "F.Paste")
			(net "RMII_OCP_BMC_CRSDV")
		)
		(pad "2" smd circle
			(at 0.40005 0)
			(size 0 0)
			(layers "F.Cu" "F.Mask" "F.Paste")
			(net "GND")
		)
	)
)
